# BASEBOARD_FAB2 (Tioga Pass) — schematic netlist excerpt (pin names and nets, part order shuffled) for the footprints in the layout excerpt that follows; sources: Cadence DE-HDL packaged netlist, KiCad conversion of Wiwynn_Tioga_Pass_MB.brd

J4G3  SCONN288_H44441004  SCONN  pkg PIP  page 47
  \12v\(1)  = P12V_NVDIMM_ABC
  VSS(93)  = GND
  DQ(4)  = M_C_DQ<5>
  VSS(92)  = GND
  DQ(0)  = M_C_DQ<1>
  VSS(91)  = GND
  DQS9P  = M_C_DQS_DP<9>
  DQS9N  = M_C_DQS_DN<9>
  VSS(90)  = GND
  DQ(6)  = M_C_DQ<7>
  VSS(89)  = GND
  DQ(2)  = M_C_DQ<3>
  VSS(88)  = GND
  DQ(12)  = M_C_DQ<13>
  VSS(87)  = GND
  DQ(8)  = M_C_DQ<9>
  VSS(86)  = GND
  DQS10P  = M_C_DQS_DP<10>
  DQS10N  = M_C_DQS_DN<10>
  VSS(85)  = GND
  DQ(14)  = M_C_DQ<15>
  VSS(84)  = GND
  DQ(10)  = M_C_DQ<11>
  VSS(83)  = GND
  DQ(20)  = M_C_DQ<21>
  VSS(82)  = GND
  DQ(16)  = M_C_DQ<17>
  VSS(81)  = GND
  DQS11P  = M_C_DQS_DP<11>
  DQS11N  = M_C_DQS_DN<11>
  VSS(80)  = GND
  DQ(22)  = M_C_DQ<23>
  VSS(79)  = GND
  DQ(18)  = M_C_DQ<19>
  VSS(78)  = GND
  DQ(28)  = M_C_DQ<29>
  VSS(77)  = GND
  DQ(24)  = M_C_DQ<25>
  VSS(76)  = GND
  DQS12P  = M_C_DQS_DP<12>
  DQS12N  = M_C_DQS_DN<12>
  VSS(75)  = GND
  DQ(30)  = M_C_DQ<31>
  VSS(74)  = GND
  DQ(26)  = M_C_DQ<27>
  VSS(73)  = GND
  CB(4)  = M_C_ECC<5>
  VSS(72)  = GND
  CB(0)  = M_C_ECC<1>
  VSS(71)  = GND
  DQS17P  = M_C_DQS_DP<17>
  DQS17N  = M_C_DQS_DN<17>
  VSS(70)  = GND
  CB(6)  = M_C_ECC<7>
  VSS(69)  = GND
  CB(2)  = M_C_ECC<3>
  VSS(68)  = GND
  RESET_N  = M_ABC_RST_N
  VDD(25)  = PVDDQ_ABC
  CKE(0)  = M_C_CKE<0>
  VDD(24)  = PVDDQ_ABC
  ACT_N  = M_C_ACT_N
  BG(0)  = M_C_BG<0>
  VDD(23)  = PVDDQ_ABC
  A12  = M_C_MA<12>
  A9  = M_C_MA<9>
  VDD(22)  = PVDDQ_ABC
  A8  = M_C_MA<8>
  A6  = M_C_MA<6>
  VDD(21)  = PVDDQ_ABC
  A3  = M_C_MA<3>
  A1  = M_C_MA<1>
  VDD(20)  = PVDDQ_ABC
  CK0P  = M_C_CLK_DP<0>
  CK0N  = M_C_CLK_DN<0>
  VDD(19)  = PVDDQ_ABC
  VTT(1)  = PVTT_ABC
  EVENT_N  = FM_DIMM_EVENT_COD_N
  A0  = M_C_MA<0>
  VDD(18)  = PVDDQ_ABC
  BA(0)  = M_C_BA<0>
  A16_RAS_N  = M_C_MA<16>
  VDD(17)  = PVDDQ_ABC
  S0_N  = M_C_CS_N<0>
  VDD(16)  = PVDDQ_ABC
  A15_CAS_N  = M_C_MA<15>
  ODT(0)  = M_C_ODT<0>
  VDD(15)  = PVDDQ_ABC
  S1_N  = M_C_CS_N<1>
  VDD(14)  = PVDDQ_ABC
  ODT(1)  = M_C_ODT<1>
  VDD(13)  = PVDDQ_ABC
  S2_N_C(0)  = M_C_CS_N<2>
  VSS(67)  = GND
  DQ(36)  = M_C_DQ<37>
  VSS(66)  = GND
  DQ(32)  = M_C_DQ<33>
  VSS(65)  = GND
  DQS13P  = M_C_DQS_DP<13>
  DQS13N  = M_C_DQS_DN<13>
  VSS(64)  = GND
  DQ(38)  = M_C_DQ<39>
  VSS(63)  = GND
  DQ(34)  = M_C_DQ<35>
  VSS(62)  = GND
  DQ(44)  = M_C_DQ<45>
  VSS(61)  = GND
  DQ(40)  = M_C_DQ<41>
  VSS(60)  = GND
  DQS14P  = M_C_DQS_DP<14>
  DQS14N  = M_C_DQS_DN<14>
  VSS(59)  = GND
  DQ(46)  = M_C_DQ<47>
  VSS(58)  = GND
  DQ(42)  = M_C_DQ<43>
  VSS(57)  = GND
  DQ(52)  = M_C_DQ<53>
  VSS(56)  = GND
  DQ(48)  = M_C_DQ<49>
  VSS(55)  = GND
  DQS15P  = M_C_DQS_DP<15>
  DQS15N  = M_C_DQS_DN<15>
  VSS(54)  = GND
  DQ(54)  = M_C_DQ<55>
  VSS(53)  = GND
  DQ(50)  = M_C_DQ<51>
  VSS(52)  = GND
  DQ(60)  = M_C_DQ<61>
  VSS(51)  = GND
  DQ(56)  = M_C_DQ<57>
  VSS(50)  = GND
  DQS16P  = M_C_DQS_DP<16>
  DQS16N  = M_C_DQS_DN<16>
  VSS(49)  = GND
  DQ(62)  = M_C_DQ<63>
  VSS(48)  = GND
  DQ(58)  = M_C_DQ<59>
  VSS(47)  = GND
  SA(0)  = GND
  SA(1)  = GND
  SCL  = SMB_DDR_ABC_VPP_SCL
  VPP(4)  = PVPP_ABC
  VPP(3)  = PVPP_ABC
  RFU(2)  = TP_CH_C_DIMM_C0_RFU_2
  \12v\(0)  = P12V_NVDIMM_ABC
  VREFCA  = M_C_VREF
  VSS(46)  = GND
  DQ(5)  = M_C_DQ<4>
  VSS(45)  = GND
  DQ(1)  = M_C_DQ<0>
  VSS(44)  = GND
  DQS0N  = M_C_DQS_DN<0>
  DQS0P  = M_C_DQS_DP<0>
  VSS(43)  = GND
  DQ(7)  = M_C_DQ<6>
  VSS(42)  = GND
  DQ(3)  = M_C_DQ<2>
  VSS(41)  = GND
  DQ(13)  = M_C_DQ<12>
  VSS(40)  = GND
  DQ(9)  = M_C_DQ<8>
  VSS(39)  = GND
  DQS1N  = M_C_DQS_DN<1>
  DQS1P  = M_C_DQS_DP<1>
  VSS(38)  = GND
  DQ(15)  = M_C_DQ<14>
  VSS(37)  = GND
  DQ(11)  = M_C_DQ<10>
  VSS(36)  = GND
  DQ(21)  = M_C_DQ<20>
  VSS(35)  = GND
  DQ(17)  = M_C_DQ<16>
  VSS(34)  = GND
  DQS2N  = M_C_DQS_DN<2>
  DQS2P  = M_C_DQS_DP<2>
  VSS(33)  = GND
  DQ(23)  = M_C_DQ<22>
  VSS(32)  = GND
  DQ(19)  = M_C_DQ<18>
  VSS(31)  = GND
  DQ(29)  = M_C_DQ<28>
  VSS(30)  = GND
  DQ(25)  = M_C_DQ<24>
  VSS(29)  = GND
  DQS3N  = M_C_DQS_DN<3>
  DQS3P  = M_C_DQS_DP<3>
  VSS(28)  = GND
  DQ(31)  = M_C_DQ<30>
  VSS(27)  = GND
  DQ(27)  = M_C_DQ<26>
  VSS(26)  = GND
  CB(5)  = M_C_ECC<4>
  VSS(25)  = GND
  CB(1)  = M_C_ECC<0>
  VSS(24)  = GND
  DQS8N  = M_C_DQS_DN<8>
  DQS8P  = M_C_DQS_DP<8>
  VSS(23)  = GND
  CB(7)  = M_C_ECC<6>
  VSS(22)  = GND
  CB(3)  = M_C_ECC<2>
  VSS(21)  = GND
  CKE(1)  = M_C_CKE<1>
  VDD(12)  = PVDDQ_ABC
  RFU(0)  = TP_CH_C_DIMM_C0_RFU_0
  VDD(11)  = PVDDQ_ABC
  BG(1)  = M_C_BG<1>
  ALERT_N  = M_C_ALERT_N
  VDD(10)  = PVDDQ_ABC
  A11  = M_C_MA<11>
  A7  = M_C_MA<7>
  VDD(9)  = PVDDQ_ABC
  A5  = M_C_MA<5>
  A4  = M_C_MA<4>
  VDD(8)  = PVDDQ_ABC
  A2  = M_C_MA<2>
  VDD(7)  = PVDDQ_ABC
  CK1P  = M_C_CLK_DP<1>
  CK1N  = M_C_CLK_DN<1>
  VDD(6)  = PVDDQ_ABC
  VTT(0)  = PVTT_ABC
  PAR  = M_C_PAR
  VDD(5)  = PVDDQ_ABC
  BA(1)  = M_C_BA<1>
  A10  = M_C_MA<10>
  VDD(4)  = PVDDQ_ABC
  RFU(1)  = TP_CH_C_DIMM_C0_RFU_1
  A14_WE_N  = M_C_MA<14>
  VDD(3)  = PVDDQ_ABC
  SAVE_N_NC  = FM_ADR_COMPLETE_ABC_N
  VDD(2)  = PVDDQ_ABC
  A13  = M_C_MA<13>
  VDD(1)  = PVDDQ_ABC
  A17  = M_C_MA<17>
  C(2)  = M_C_C<2>
  VDD(0)  = PVDDQ_ABC
  S3_N_C(1)  = M_C_CS_N<3>
  SA(2)  = PVPP_ABC
  VSS(20)  = GND
  DQ(37)  = M_C_DQ<36>
  VSS(19)  = GND
  DQ(33)  = M_C_DQ<32>
  VSS(18)  = GND
  DQS4N  = M_C_DQS_DN<4>
  DQS4P  = M_C_DQS_DP<4>
  VSS(17)  = GND
  DQ(39)  = M_C_DQ<38>
  VSS(16)  = GND
  DQ(35)  = M_C_DQ<34>
  VSS(15)  = GND
  DQ(45)  = M_C_DQ<44>
  VSS(14)  = GND
  DQ(41)  = M_C_DQ<40>
  VSS(13)  = GND
  DQS5N  = M_C_DQS_DN<5>
  DQS5P  = M_C_DQS_DP<5>
  VSS(12)  = GND
  DQ(47)  = M_C_DQ<46>
  VSS(11)  = GND
  DQ(43)  = M_C_DQ<42>
  VSS(10)  = GND
  DQ(53)  = M_C_DQ<52>
  VSS(9)  = GND
  DQ(49)  = M_C_DQ<48>
  VSS(8)  = GND
  DQS6N  = M_C_DQS_DN<6>
  DQS6P  = M_C_DQS_DP<6>
  VSS(7)  = GND
  DQ(55)  = M_C_DQ<54>
  VSS(6)  = GND
  DQ(51)  = M_C_DQ<50>
  VSS(5)  = GND
  DQ(61)  = M_C_DQ<60>
  VSS(4)  = GND
  DQ(57)  = M_C_DQ<56>
  VSS(3)  = GND
  DQS7N  = M_C_DQS_DN<7>
  DQS7P  = M_C_DQS_DP<7>
  VSS(2)  = GND
  DQ(63)  = M_C_DQ<62>
  VSS(1)  = GND
  DQ(59)  = M_C_DQ<58>
  VSS(0)  = GND
  VDDSPD  = PVPP_ABC
  SDA  = SMB_DDR_ABC_VPP_SDA
  VPP(1)  = PVPP_ABC
  VPP(0)  = PVPP_ABC
  VPP(2)  = PVPP_ABC

(kicad_pcb
	(version 20260206)
	(generator "pcbnew")
	(generator_version "10.0")
	(general
		(thickness 1.6)
		(legacy_teardrops no)
	)
	(paper "A4")
	(title_block
		(title "Wiwynn_Tioga_Pass_MB.brd")
		(comment 1 "Tioga Pass / footprint 1441 of 4770 (J4G3), pads 1-51 of 291")
	)
	(layers
		(0 "F.Cu" signal "TOP")
		(4 "In1.Cu" signal "L2GND")
		(6 "In2.Cu" signal "L3")
		(8 "In3.Cu" signal "L4GND")
		(10 "In4.Cu" signal "L5")
		(12 "In5.Cu" signal "L6GND")
		(14 "In6.Cu" signal "L7VCC")
		(16 "In7.Cu" signal "L8VCC")
		(18 "In8.Cu" signal "L9GND")
		(20 "In9.Cu" signal "L10")
		(22 "In10.Cu" signal "L11GND")
		(24 "In11.Cu" signal "L12")
		(26 "In12.Cu" signal "L13GND")
		(2 "B.Cu" signal "BOTTOM")
		(9 "F.Adhes" user "F.Adhesive")
		(11 "B.Adhes" user "B.Adhesive")
		(13 "F.Paste" user "Package Geometry/Pastemask Top")
		(15 "B.Paste" user "Package Geometry/Pastemask Bottom")
		(5 "F.SilkS" user "Ref Des/Silkscreen Top")
		(7 "B.SilkS" user "Ref Des/Silkscreen Bottom")
		(1 "F.Mask" user "Board Geometry/Soldermask Top")
		(3 "B.Mask" user "Board Geometry/Soldermask Bottom")
		(17 "Dwgs.User" user "User.Drawings")
		(19 "Cmts.User" user "User.Comments")
		(21 "Eco1.User" user "User.Eco1")
		(23 "Eco2.User" user "User.Eco2")
		(25 "Edge.Cuts" user "Board Geometry/Outline")
		(27 "Margin" user)
		(31 "F.CrtYd" user "Package Geometry/Place Bound Top")
		(29 "B.CrtYd" user "Package Geometry/Place Bound Bottom")
		(35 "F.Fab" user "Ref Des/Assembly Top")
		(33 "B.Fab" user "Ref Des/Assembly Bottom")
	)
	(footprint ""
		(layer "F.Cu")
		(at 194.700398 3.778758 90)
		(property "Reference" "J4G3"
			(at 6.800088 37.20211 0)
			(unlocked yes)
			(layer "F.SilkS")
			(effects
				(font
					(size 0.7874 0.5842)
					(thickness 0.1524)
				)
				(justify left)
			)
		)
		(property "Value" ""
			(at 0 0 90)
			(layer "F.Fab")
			(effects
				(font
					(size 1.27 1.27)
				)
			)
		)
		(duplicate_pad_numbers_are_jumpers no)
		(pad "" thru_hole circle
			(at 2.29997 -5.649976 90)
			(size 2.8194 2.8194)
			(drill 2.4384)
			(layers "*.Cu" "*.Mask")
			(remove_unused_layers no)
			(clearance 0.127)
			(thermal_gap 0.127)
		)
		(pad "" thru_hole oval
			(at 2.29997 68.90004 90)
			(size 2.8194 1.5748)
			(drill oval 2.4384 1.1938)
			(layers "*.Cu" "*.Mask")
			(remove_unused_layers no)
			(clearance 0.127)
			(thermal_gap 0.127)
		)
		(pad "" thru_hole circle
			(at 2.29997 132.299964 90)
			(size 2.8194 2.8194)
			(drill 2.4384)
			(layers "*.Cu" "*.Mask")
			(remove_unused_layers no)
			(clearance 0.127)
			(thermal_gap 0.127)
		)
		(pad "1" smd rect
			(at 0 0 90)
			(size 1.8034 0.508)
			(layers "F.Cu" "F.Mask" "F.Paste")
			(net "P12V_NVDIMM_ABC")
		)
		(pad "2" smd rect
			(at 0 0.849884 90)
			(size 1.8034 0.508)
			(layers "F.Cu" "F.Mask" "F.Paste")
			(net "GND")
		)
		(pad "3" smd rect
			(at 0 1.700022 90)
			(size 1.8034 0.508)
			(layers "F.Cu" "F.Mask" "F.Paste")
			(net "M_C_DQ<5>")
		)
		(pad "4" smd rect
			(at 0 2.549906 90)
			(size 1.8034 0.508)
			(layers "F.Cu" "F.Mask" "F.Paste")
			(net "GND")
		)
		(pad "5" smd rect
			(at 0 3.400044 90)
			(size 1.8034 0.508)
			(layers "F.Cu" "F.Mask" "F.Paste")
			(net "M_C_DQ<1>")
		)
		(pad "6" smd rect
			(at 0 4.249928 90)
			(size 1.8034 0.508)
			(layers "F.Cu" "F.Mask" "F.Paste")
			(net "GND")
		)
		(pad "7" smd rect
			(at 0 5.100066 90)
			(size 1.8034 0.508)
			(layers "F.Cu" "F.Mask" "F.Paste")
			(net "M_C_DQS_DP<9>")
		)
		(pad "8" smd rect
			(at 0 5.94995 90)
			(size 1.8034 0.508)
			(layers "F.Cu" "F.Mask" "F.Paste")
			(net "M_C_DQS_DN<9>")
		)
		(pad "9" smd rect
			(at 0 6.800088 90)
			(size 1.8034 0.508)
			(layers "F.Cu" "F.Mask" "F.Paste")
			(net "GND")
		)
		(pad "10" smd rect
			(at 0 7.649972 90)
			(size 1.8034 0.508)
			(layers "F.Cu" "F.Mask" "F.Paste")
			(net "M_C_DQ<7>")
		)
		(pad "11" smd rect
			(at 0 8.50011 90)
			(size 1.8034 0.508)
			(layers "F.Cu" "F.Mask" "F.Paste")
			(net "GND")
		)
		(pad "12" smd rect
			(at 0 9.349994 90)
			(size 1.8034 0.508)
			(layers "F.Cu" "F.Mask" "F.Paste")
			(net "M_C_DQ<3>")
		)
		(pad "13" smd rect
			(at 0 10.199878 90)
			(size 1.8034 0.508)
			(layers "F.Cu" "F.Mask" "F.Paste")
			(net "GND")
		)
		(pad "14" smd rect
			(at 0 11.050016 90)
			(size 1.8034 0.508)
			(layers "F.Cu" "F.Mask" "F.Paste")
			(net "M_C_DQ<13>")
		)
		(pad "15" smd rect
			(at 0 11.8999 90)
			(size 1.8034 0.508)
			(layers "F.Cu" "F.Mask" "F.Paste")
			(net "GND")
		)
		(pad "16" smd rect
			(at 0 12.750038 90)
			(size 1.8034 0.508)
			(layers "F.Cu" "F.Mask" "F.Paste")
			(net "M_C_DQ<9>")
		)
		(pad "17" smd rect
			(at 0 13.599922 90)
			(size 1.8034 0.508)
			(layers "F.Cu" "F.Mask" "F.Paste")
			(net "GND")
		)
		(pad "18" smd rect
			(at 0 14.45006 90)
			(size 1.8034 0.508)
			(layers "F.Cu" "F.Mask" "F.Paste")
			(net "M_C_DQS_DP<10>")
		)
		(pad "19" smd rect
			(at 0 15.299944 90)
			(size 1.8034 0.508)
			(layers "F.Cu" "F.Mask" "F.Paste")
			(net "M_C_DQS_DN<10>")
		)
		(pad "20" smd rect
			(at 0 16.150082 90)
			(size 1.8034 0.508)
			(layers "F.Cu" "F.Mask" "F.Paste")
			(net "GND")
		)
		(pad "21" smd rect
			(at 0 16.999966 90)
			(size 1.8034 0.508)
			(layers "F.Cu" "F.Mask" "F.Paste")
			(net "M_C_DQ<15>")
		)
		(pad "22" smd rect
			(at 0 17.850104 90)
			(size 1.8034 0.508)
			(layers "F.Cu" "F.Mask" "F.Paste")
			(net "GND")
		)
		(pad "23" smd rect
			(at 0 18.699988 90)
			(size 1.8034 0.508)
			(layers "F.Cu" "F.Mask" "F.Paste")
			(net "M_C_DQ<11>")
		)
		(pad "24" smd rect
			(at 0 19.550126 90)
			(size 1.8034 0.508)
			(layers "F.Cu" "F.Mask" "F.Paste")
			(net "GND")
		)
		(pad "25" smd rect
			(at 0 20.40001 90)
			(size 1.8034 0.508)
			(layers "F.Cu" "F.Mask" "F.Paste")
			(net "M_C_DQ<21>")
		)
		(pad "26" smd rect
			(at 0 21.249894 90)
			(size 1.8034 0.508)
			(layers "F.Cu" "F.Mask" "F.Paste")
			(net "GND")
		)
		(pad "27" smd rect
			(at 0 22.100032 90)
			(size 1.8034 0.508)
			(layers "F.Cu" "F.Mask" "F.Paste")
			(net "M_C_DQ<17>")
		)
		(pad "28" smd rect
			(at 0 22.949916 90)
			(size 1.8034 0.508)
			(layers "F.Cu" "F.Mask" "F.Paste")
			(net "GND")
		)
		(pad "29" smd rect
			(at 0 23.800054 90)
			(size 1.8034 0.508)
			(layers "F.Cu" "F.Mask" "F.Paste")
			(net "M_C_DQS_DP<11>")
		)
		(pad "30" smd rect
			(at 0 24.649938 90)
			(size 1.8034 0.508)
			(layers "F.Cu" "F.Mask" "F.Paste")
			(net "M_C_DQS_DN<11>")
		)
		(pad "31" smd rect
			(at 0 25.500076 90)
			(size 1.8034 0.508)
			(layers "F.Cu" "F.Mask" "F.Paste")
			(net "GND")
		)
		(pad "32" smd rect
			(at 0 26.34996 90)
			(size 1.8034 0.508)
			(layers "F.Cu" "F.Mask" "F.Paste")
			(net "M_C_DQ<23>")
		)
		(pad "33" smd rect
			(at 0 27.200098 90)
			(size 1.8034 0.508)
			(layers "F.Cu" "F.Mask" "F.Paste")
			(net "GND")
		)
		(pad "34" smd rect
			(at 0 28.049982 90)
			(size 1.8034 0.508)
			(layers "F.Cu" "F.Mask" "F.Paste")
			(net "M_C_DQ<19>")
		)
		(pad "35" smd rect
			(at 0 28.90012 90)
			(size 1.8034 0.508)
			(layers "F.Cu" "F.Mask" "F.Paste")
			(net "GND")
		)
		(pad "36" smd rect
			(at 0 29.750004 90)
			(size 1.8034 0.508)
			(layers "F.Cu" "F.Mask" "F.Paste")
			(net "M_C_DQ<29>")
		)
		(pad "37" smd rect
			(at 0 30.599888 90)
			(size 1.8034 0.508)
			(layers "F.Cu" "F.Mask" "F.Paste")
			(net "GND")
		)
		(pad "38" smd rect
			(at 0 31.450026 90)
			(size 1.8034 0.508)
			(layers "F.Cu" "F.Mask" "F.Paste")
			(net "M_C_DQ<25>")
		)
		(pad "39" smd rect
			(at 0 32.29991 90)
			(size 1.8034 0.508)
			(layers "F.Cu" "F.Mask" "F.Paste")
			(net "GND")
		)
		(pad "40" smd rect
			(at 0 33.150048 90)
			(size 1.8034 0.508)
			(layers "F.Cu" "F.Mask" "F.Paste")
			(net "M_C_DQS_DP<12>")
		)
		(pad "41" smd rect
			(at 0 33.999932 90)
			(size 1.8034 0.508)
			(layers "F.Cu" "F.Mask" "F.Paste")
			(net "M_C_DQS_DN<12>")
		)
		(pad "42" smd rect
			(at 0 34.85007 90)
			(size 1.8034 0.508)
			(layers "F.Cu" "F.Mask" "F.Paste")
			(net "GND")
		)
		(pad "43" smd rect
			(at 0 35.699954 90)
			(size 1.8034 0.508)
			(layers "F.Cu" "F.Mask" "F.Paste")
			(net "M_C_DQ<31>")
		)
		(pad "44" smd rect
			(at 0 36.550092 90)
			(size 1.8034 0.508)
			(layers "F.Cu" "F.Mask" "F.Paste")
			(net "GND")
		)
		(pad "45" smd rect
			(at 0 37.399976 90)
			(size 1.8034 0.508)
			(layers "F.Cu" "F.Mask" "F.Paste")
			(net "M_C_DQ<27>")
		)
		(pad "46" smd rect
			(at 0 38.250114 90)
			(size 1.8034 0.508)
			(layers "F.Cu" "F.Mask" "F.Paste")
			(net "GND")
		)
		(pad "47" smd rect
			(at 0 39.099998 90)
			(size 1.8034 0.508)
			(layers "F.Cu" "F.Mask" "F.Paste")
			(net "M_C_ECC<5>")
		)
		(pad "48" smd rect
			(at 0 39.949882 90)
			(size 1.8034 0.508)
			(layers "F.Cu" "F.Mask" "F.Paste")
			(net "GND")
		)
	)
)
